(kicad_pcb
	(version 20260206)
	(generator "pcbnew")
	(generator_version "10.0")
	(general
		(thickness 1.6)
		(legacy_teardrops no)
	)
	(paper "A4")
	(title_block
		(title "v1-chassis-manager — T6M_CM_d_v01_1031_1645.brd")
		(comment 1 "Open CloudServer (Microsoft) / footprints 475-484 of 2512")
	)
	(layers
		(0 "F.Cu" signal "TOP")
		(4 "In1.Cu" signal "GND1")
		(6 "In2.Cu" signal "IN1")
		(8 "In3.Cu" signal "VCC1")
		(10 "In4.Cu" signal "VCC2")
		(12 "In5.Cu" signal "GND2")
		(14 "In6.Cu" signal "IN2")
		(16 "In7.Cu" signal "IN3")
		(18 "In8.Cu" signal "GND3")
		(2 "B.Cu" signal "BOTTOM")
		(9 "F.Adhes" user "F.Adhesive")
		(11 "B.Adhes" user "B.Adhesive")
		(13 "F.Paste" user "Package Geometry/Pastemask Top")
		(15 "B.Paste" user "Package Geometry/Pastemask Bottom")
		(5 "F.SilkS" user "Ref Des/Silkscreen Top")
		(7 "B.SilkS" user "Ref Des/Silkscreen Bottom")
		(1 "F.Mask" user "Board Geometry/Soldermask Top")
		(3 "B.Mask" user "Board Geometry/Soldermask Bottom")
		(17 "Dwgs.User" user "User.Drawings")
		(19 "Cmts.User" user "User.Comments")
		(21 "Eco1.User" user "User.Eco1")
		(23 "Eco2.User" user "User.Eco2")
		(25 "Edge.Cuts" user "Board Geometry/Outline")
		(27 "Margin" user)
		(31 "F.CrtYd" user "Package Geometry/Place Bound Top")
		(29 "B.CrtYd" user "Package Geometry/Place Bound Bottom")
		(35 "F.Fab" user "Ref Des/Assembly Top")
		(33 "B.Fab" user "Ref Des/Assembly Bottom")
	)
	(footprint ""
		(layer "F.Cu")
		(at 53.95976 -185.205624 -90)
		(property "Reference" "R818"
			(at -4.006088 0.034544 90)
			(unlocked yes)
			(layer "F.SilkS")
			(effects
				(font
					(size 0.7874 0.5842)
					(thickness 0.1524)
				)
				(justify left)
			)
		)
		(property "Value" ""
			(at 0 0 270)
			(layer "F.Fab")
			(effects
				(font
					(size 1.27 1.27)
				)
			)
		)
		(duplicate_pad_numbers_are_jumpers no)
		(fp_line
			(start -0.7874 0.406146)
			(end -0.7874 -0.406146)
			(stroke
				(width 0.1524)
				(type default)
			)
			(layer "F.SilkS")
		)
		(fp_line
			(start 0.7874 0.406146)
			(end -0.7874 0.406146)
			(stroke
				(width 0.1524)
				(type default)
			)
			(layer "F.SilkS")
		)
		(fp_line
			(start -0.7874 -0.406146)
			(end 0.7874 -0.406146)
			(stroke
				(width 0.1524)
				(type default)
			)
			(layer "F.SilkS")
		)
		(fp_line
			(start 0.7874 -0.406146)
			(end 0.7874 0.406146)
			(stroke
				(width 0.1524)
				(type default)
			)
			(layer "F.SilkS")
		)
		(fp_poly
			(pts
				(xy -0.508 0.2794) (xy -0.508 0.2286) (xy -0.635 0.2286) (xy -0.635 -0.254) (xy -0.5334 -0.254)
				(xy -0.5334 -0.2794) (xy 0.5334 -0.2794) (xy 0.5334 -0.254) (xy 0.635 -0.254) (xy 0.635 0.254) (xy 0.5334 0.254)
				(xy 0.5334 0.2794)
			)
			(stroke
				(width 0)
				(type default)
			)
			(fill no)
			(layer "F.CrtYd")
		)
		(pad "1" smd rect
			(at 0.40005 0 270)
			(size 0.4572 0.508)
			(layers "F.Cu" "F.Mask" "F.Paste")
			(net "I2C_PSU1_SDA")
		)
		(pad "2" smd rect
			(at -0.40005 0 270)
			(size 0.4572 0.508)
			(layers "F.Cu" "F.Mask" "F.Paste")
			(net "I2C_PSU1_R_SDA")
		)
	)
	(footprint ""
		(layer "F.Cu")
		(at 16.04137 -56.881776)
		(property "Reference" "C501"
			(at 14.149324 0.471424 0)
			(unlocked yes)
			(layer "F.SilkS")
			(effects
				(font
					(size 0.7874 0.5842)
					(thickness 0.1524)
				)
			)
		)
		(property "Value" ""
			(at 0 0 0)
			(layer "F.Fab")
			(effects
				(font
					(size 1.27 1.27)
				)
			)
		)
		(duplicate_pad_numbers_are_jumpers no)
		(fp_line
			(start -1.2954 -0.5842)
			(end 1.2954 -0.5842)
			(stroke
				(width 0.1524)
				(type default)
			)
			(layer "F.SilkS")
		)
		(fp_line
			(start -1.2954 0.5842)
			(end -1.2954 -0.5842)
			(stroke
				(width 0.1524)
				(type default)
			)
			(layer "F.SilkS")
		)
		(fp_line
			(start 0 -0.5842)
			(end 0 0.5842)
			(stroke
				(width 0.1524)
				(type default)
			)
			(layer "F.SilkS")
		)
		(fp_line
			(start 1.2954 -0.5842)
			(end 1.2954 0.5842)
			(stroke
				(width 0.1524)
				(type default)
			)
			(layer "F.SilkS")
		)
		(fp_line
			(start 1.2954 0.5842)
			(end -1.2954 0.5842)
			(stroke
				(width 0.1524)
				(type default)
			)
			(layer "F.SilkS")
		)
		(fp_poly
			(pts
				(xy 0.8636 -0.4572) (xy 0.8636 -0.3556) (xy 1.143 -0.3556) (xy 1.143 0.3556) (xy 0.8636 0.3556)
				(xy 0.8636 0.4572) (xy -0.8636 0.4572) (xy -0.8636 0.3556) (xy -1.143 0.3556) (xy -1.143 -0.3556)
				(xy -0.8636 -0.3556) (xy -0.8636 -0.4572)
			)
			(stroke
				(width 0)
				(type default)
			)
			(fill no)
			(layer "F.CrtYd")
		)
		(fp_line
			(start -0.884936 -0.504952)
			(end 0.884936 -0.504952)
			(stroke
				(width 0.1)
				(type default)
			)
			(layer "F.Fab")
		)
		(fp_line
			(start -0.884936 0.504952)
			(end -0.884936 -0.504952)
			(stroke
				(width 0.1)
				(type default)
			)
			(layer "F.Fab")
		)
		(fp_line
			(start 0.884936 -0.504952)
			(end 0.884936 0.504952)
			(stroke
				(width 0.1)
				(type default)
			)
			(layer "F.Fab")
		)
		(fp_line
			(start 0.884936 0.504952)
			(end -0.884936 0.504952)
			(stroke
				(width 0.1)
				(type default)
			)
			(layer "F.Fab")
		)
		(pad "1" smd rect
			(at 0.7366 0 90)
			(size 0.7112 0.8128)
			(layers "F.Cu" "F.Mask" "F.Paste")
			(net "BMC_NODE1_GFX_BLUE")
		)
		(pad "2" smd rect
			(at -0.7366 0 90)
			(size 0.7112 0.8128)
			(layers "F.Cu" "F.Mask" "F.Paste")
			(net "GND")
		)
	)
	(footprint ""
		(layer "F.Cu")
		(at 140.270484 -112.534192)
		(property "Reference" "R24"
			(at 1.562862 3.197098 0)
			(unlocked yes)
			(layer "F.SilkS")
			(effects
				(font
					(size 0.7874 0.5842)
					(thickness 0.1524)
				)
				(justify left)
			)
		)
		(property "Value" ""
			(at 0 0 0)
			(layer "F.Fab")
			(effects
				(font
					(size 1.27 1.27)
				)
			)
		)
		(duplicate_pad_numbers_are_jumpers no)
		(fp_line
			(start -0.7874 -0.4064)
			(end 0.7874 -0.4064)
			(stroke
				(width 0.1524)
				(type default)
			)
			(layer "F.SilkS")
		)
		(fp_line
			(start -0.7874 0.4064)
			(end -0.7874 -0.4064)
			(stroke
				(width 0.1524)
				(type default)
			)
			(layer "F.SilkS")
		)
		(fp_line
			(start 0.7874 -0.4064)
			(end 0.7874 0.4064)
			(stroke
				(width 0.1524)
				(type default)
			)
			(layer "F.SilkS")
		)
		(fp_line
			(start 0.7874 0.4064)
			(end -0.7874 0.4064)
			(stroke
				(width 0.1524)
				(type default)
			)
			(layer "F.SilkS")
		)
		(fp_poly
			(pts
				(xy -0.508 0.2794) (xy -0.508 0.2286) (xy -0.635 0.2286) (xy -0.635 -0.254) (xy -0.5334 -0.254)
				(xy -0.5334 -0.2794) (xy 0.5334 -0.2794) (xy 0.5334 -0.254) (xy 0.635 -0.254) (xy 0.635 0.254) (xy 0.5334 0.254)
				(xy 0.5334 0.2794)
			)
			(stroke
				(width 0)
				(type default)
			)
			(fill no)
			(layer "F.CrtYd")
		)
		(pad "1" smd rect
			(at 0.40005 0)
			(size 0.4572 0.508)
			(layers "F.Cu" "F.Mask" "F.Paste")
			(net "GND")
		)
		(pad "2" smd rect
			(at -0.40005 0)
			(size 0.4572 0.508)
			(layers "F.Cu" "F.Mask" "F.Paste")
			(net "SEL_DOT_SRC5")
		)
	)
	(footprint ""
		(layer "F.Cu")
		(at 65.209166 -96.709992 90)
		(property "Reference" "R68"
			(at -54.98719 28.439364 90)
			(unlocked yes)
			(layer "F.SilkS")
			(effects
				(font
					(size 0.7874 0.5842)
					(thickness 0.1524)
				)
				(justify left)
			)
		)
		(property "Value" ""
			(at 0 0 90)
			(layer "F.Fab")
			(effects
				(font
					(size 1.27 1.27)
				)
			)
		)
		(duplicate_pad_numbers_are_jumpers no)
		(fp_line
			(start 0.7874 -0.4064)
			(end 0.7874 0.4064)
			(stroke
				(width 0.1524)
				(type default)
			)
			(layer "F.SilkS")
		)
		(fp_line
			(start -0.7874 -0.4064)
			(end 0.7874 -0.4064)
			(stroke
				(width 0.1524)
				(type default)
			)
			(layer "F.SilkS")
		)
		(fp_line
			(start 0.7874 0.4064)
			(end -0.7874 0.4064)
			(stroke
				(width 0.1524)
				(type default)
			)
			(layer "F.SilkS")
		)
		(fp_line
			(start -0.7874 0.4064)
			(end -0.7874 -0.4064)
			(stroke
				(width 0.1524)
				(type default)
			)
			(layer "F.SilkS")
		)
		(fp_poly
			(pts
				(xy -0.508 0.2794) (xy -0.508 0.2286) (xy -0.635 0.2286) (xy -0.635 -0.254) (xy -0.5334 -0.254)
				(xy -0.5334 -0.2794) (xy 0.5334 -0.2794) (xy 0.5334 -0.254) (xy 0.635 -0.254) (xy 0.635 0.254) (xy 0.5334 0.254)
				(xy 0.5334 0.2794)
			)
			(stroke
				(width 0)
				(type default)
			)
			(fill no)
			(layer "F.CrtYd")
		)
		(pad "1" smd rect
			(at 0.40005 0 90)
			(size 0.4572 0.508)
			(layers "F.Cu" "F.Mask" "F.Paste")
			(net "P3V3_NODE1")
		)
		(pad "2" smd rect
			(at -0.40005 0 90)
			(size 0.4572 0.508)
			(layers "F.Cu" "F.Mask" "F.Paste")
			(net "LPC_CPU_NODE1_CLKRUN_L")
		)
	)
	(footprint ""
		(layer "F.Cu")
		(at 105.56367 -156.619702 90)
		(property "Reference" "PC41"
			(at -2.524252 1.738884 90)
			(unlocked yes)
			(layer "F.SilkS")
			(effects
				(font
					(size 0.635 0.4064)
					(thickness 0.1524)
				)
				(justify left)
			)
		)
		(property "Value" ""
			(at 0 0 90)
			(layer "F.Fab")
			(effects
				(font
					(size 1.27 1.27)
				)
			)
		)
		(duplicate_pad_numbers_are_jumpers no)
		(fp_line
			(start 0.7874 -0.4064)
			(end 0.7874 0.4064)
			(stroke
				(width 0.1524)
				(type default)
			)
			(layer "F.SilkS")
		)
		(fp_line
			(start -0.7874 -0.4064)
			(end 0.7874 -0.4064)
			(stroke
				(width 0.1524)
				(type default)
			)
			(layer "F.SilkS")
		)
		(fp_line
			(start 0 0.381)
			(end 0 -0.381)
			(stroke
				(width 0.1524)
				(type default)
			)
			(layer "F.SilkS")
		)
		(fp_line
			(start 0.7874 0.4064)
			(end -0.7874 0.4064)
			(stroke
				(width 0.1524)
				(type default)
			)
			(layer "F.SilkS")
		)
		(fp_line
			(start -0.7874 0.4064)
			(end -0.7874 -0.4064)
			(stroke
				(width 0.1524)
				(type default)
			)
			(layer "F.SilkS")
		)
		(fp_poly
			(pts
				(xy -0.5334 0.254) (xy -0.635 0.254) (xy -0.635 0.2286) (xy -0.635 -0.254) (xy -0.5334 -0.254) (xy -0.5334 -0.2794)
				(xy 0.5334 -0.2794) (xy 0.5334 -0.254) (xy 0.635 -0.254) (xy 0.635 0.254) (xy 0.5334 0.254) (xy 0.5334 0.2794)
				(xy -0.508 0.2794) (xy -0.5334 0.2794)
			)
			(stroke
				(width 0)
				(type default)
			)
			(fill no)
			(layer "F.CrtYd")
		)
		(pad "1" smd rect
			(at 0.40005 0 90)
			(size 0.4572 0.508)
			(layers "F.Cu" "F.Mask" "F.Paste")
			(net "GND")
		)
		(pad "2" smd rect
			(at -0.40005 0 90)
			(size 0.4572 0.508)
			(layers "F.Cu" "F.Mask" "F.Paste")
			(net "P1V8_STB_NODE1_SS")
		)
	)
	(footprint ""
		(layer "F.Cu")
		(at 140.692886 -51.476656 90)
		(property "Reference" "R1024"
			(at 16.324326 30.435042 90)
			(unlocked yes)
			(layer "F.SilkS")
			(effects
				(font
					(size 0.7874 0.5842)
					(thickness 0.1524)
				)
				(justify left)
			)
		)
		(property "Value" ""
			(at 0 0 90)
			(layer "F.Fab")
			(effects
				(font
					(size 1.27 1.27)
				)
			)
		)
		(duplicate_pad_numbers_are_jumpers no)
		(fp_line
			(start 0.7874 -0.4064)
			(end 0.7874 0.4064)
			(stroke
				(width 0.1524)
				(type default)
			)
			(layer "F.SilkS")
		)
		(fp_line
			(start -0.7874 -0.4064)
			(end 0.7874 -0.4064)
			(stroke
				(width 0.1524)
				(type default)
			)
			(layer "F.SilkS")
		)
		(fp_line
			(start 0.7874 0.4064)
			(end -0.7874 0.4064)
			(stroke
				(width 0.1524)
				(type default)
			)
			(layer "F.SilkS")
		)
		(fp_line
			(start -0.7874 0.4064)
			(end -0.7874 -0.4064)
			(stroke
				(width 0.1524)
				(type default)
			)
			(layer "F.SilkS")
		)
		(fp_poly
			(pts
				(xy -0.508 0.2794) (xy -0.508 0.2286) (xy -0.635 0.2286) (xy -0.635 -0.254) (xy -0.5334 -0.254)
				(xy -0.5334 -0.2794) (xy 0.5334 -0.2794) (xy 0.5334 -0.254) (xy 0.635 -0.254) (xy 0.635 0.254) (xy 0.5334 0.254)
				(xy 0.5334 0.2794)
			)
			(stroke
				(width 0)
				(type default)
			)
			(fill no)
			(layer "F.CrtYd")
		)
		(pad "1" smd rect
			(at 0.40005 0 90)
			(size 0.4572 0.508)
			(layers "F.Cu" "F.Mask" "F.Paste")
			(net "GND")
		)
		(pad "2" smd rect
			(at -0.40005 0 90)
			(size 0.4572 0.508)
			(layers "F.Cu" "F.Mask" "F.Paste")
			(net "UART_TX_P2")
		)
	)
	(footprint ""
		(layer "F.Cu")
		(at 10.257028 -138.946636)
		(property "Reference" "C555"
			(at -4.623562 4.578858 90)
			(unlocked yes)
			(layer "F.SilkS")
			(effects
				(font
					(size 0.7874 0.5842)
					(thickness 0.1524)
				)
				(justify left)
			)
		)
		(property "Value" ""
			(at 0 0 0)
			(layer "F.Fab")
			(effects
				(font
					(size 1.27 1.27)
				)
			)
		)
		(duplicate_pad_numbers_are_jumpers no)
		(fp_line
			(start -0.7874 -0.4064)
			(end 0.7874 -0.4064)
			(stroke
				(width 0.1524)
				(type default)
			)
			(layer "F.SilkS")
		)
		(fp_line
			(start -0.7874 0.4064)
			(end -0.7874 -0.4064)
			(stroke
				(width 0.1524)
				(type default)
			)
			(layer "F.SilkS")
		)
		(fp_line
			(start 0 0.381)
			(end 0 -0.381)
			(stroke
				(width 0.1524)
				(type default)
			)
			(layer "F.SilkS")
		)
		(fp_line
			(start 0.7874 -0.4064)
			(end 0.7874 0.4064)
			(stroke
				(width 0.1524)
				(type default)
			)
			(layer "F.SilkS")
		)
		(fp_line
			(start 0.7874 0.4064)
			(end -0.7874 0.4064)
			(stroke
				(width 0.1524)
				(type default)
			)
			(layer "F.SilkS")
		)
		(fp_poly
			(pts
				(xy -0.5334 0.254) (xy -0.635 0.254) (xy -0.635 0.2286) (xy -0.635 -0.254) (xy -0.5334 -0.254) (xy -0.5334 -0.2794)
				(xy 0.5334 -0.2794) (xy 0.5334 -0.254) (xy 0.635 -0.254) (xy 0.635 0.254) (xy 0.5334 0.254) (xy 0.5334 0.2794)
				(xy -0.508 0.2794) (xy -0.5334 0.2794)
			)
			(stroke
				(width 0)
				(type default)
			)
			(fill no)
			(layer "F.CrtYd")
		)
		(pad "1" smd rect
			(at 0.40005 0)
			(size 0.4572 0.508)
			(layers "F.Cu" "F.Mask" "F.Paste")
			(net "P3V3_NODE1")
		)
		(pad "2" smd rect
			(at -0.40005 0)
			(size 0.4572 0.508)
			(layers "F.Cu" "F.Mask" "F.Paste")
			(net "GND")
		)
	)
	(footprint ""
		(layer "F.Cu")
		(at 104.548432 -130.16103 -90)
		(property "Reference" "PR79"
			(at 5.362194 7.159752 90)
			(unlocked yes)
			(layer "F.SilkS")
			(effects
				(font
					(size 0.7874 0.5842)
					(thickness 0.1524)
				)
				(justify left)
			)
		)
		(property "Value" ""
			(at 0 0 270)
			(layer "F.Fab")
			(effects
				(font
					(size 1.27 1.27)
				)
			)
		)
		(duplicate_pad_numbers_are_jumpers no)
		(fp_line
			(start -0.7874 0.4064)
			(end -0.7874 -0.4064)
			(stroke
				(width 0.1524)
				(type default)
			)
			(layer "F.SilkS")
		)
		(fp_line
			(start 0.7874 0.4064)
			(end -0.7874 0.4064)
			(stroke
				(width 0.1524)
				(type default)
			)
			(layer "F.SilkS")
		)
		(fp_line
			(start -0.7874 -0.4064)
			(end 0.7874 -0.4064)
			(stroke
				(width 0.1524)
				(type default)
			)
			(layer "F.SilkS")
		)
		(fp_line
			(start 0.7874 -0.4064)
			(end 0.7874 0.4064)
			(stroke
				(width 0.1524)
				(type default)
			)
			(layer "F.SilkS")
		)
		(fp_poly
			(pts
				(xy -0.508 0.2794) (xy -0.508 0.2286) (xy -0.635 0.2286) (xy -0.635 -0.254) (xy -0.5334 -0.254)
				(xy -0.5334 -0.2794) (xy 0.5334 -0.2794) (xy 0.5334 -0.254) (xy 0.635 -0.254) (xy 0.635 0.254) (xy 0.5334 0.254)
				(xy 0.5334 0.2794)
			)
			(stroke
				(width 0)
				(type default)
			)
			(fill no)
			(layer "F.CrtYd")
		)
		(pad "1" smd rect
			(at 0.40005 0 270)
			(size 0.4572 0.508)
			(layers "F.Cu" "F.Mask" "F.Paste")
			(net "P3V3_NODE1")
		)
		(pad "2" smd rect
			(at -0.40005 0 270)
			(size 0.4572 0.508)
			(layers "F.Cu" "F.Mask" "F.Paste")
			(net "VR_PVCCP_NODE1_EN")
		)
	)
	(footprint ""
		(layer "F.Cu")
		(at 83.67776 -188.126624 90)
		(property "Reference" "C591"
			(at 4.548886 -1.847088 90)
			(unlocked yes)
			(layer "F.SilkS")
			(effects
				(font
					(size 0.7874 0.5842)
					(thickness 0.1524)
				)
				(justify left)
			)
		)
		(property "Value" ""
			(at 0 0 90)
			(layer "F.Fab")
			(effects
				(font
					(size 1.27 1.27)
				)
			)
		)
		(duplicate_pad_numbers_are_jumpers no)
		(fp_line
			(start 0.7874 -0.4064)
			(end 0.7874 0.4064)
			(stroke
				(width 0.1524)
				(type default)
			)
			(layer "F.SilkS")
		)
		(fp_line
			(start -0.7874 -0.4064)
			(end 0.7874 -0.4064)
			(stroke
				(width 0.1524)
				(type default)
			)
			(layer "F.SilkS")
		)
		(fp_line
			(start 0 0.381)
			(end 0 -0.381)
			(stroke
				(width 0.1524)
				(type default)
			)
			(layer "F.SilkS")
		)
		(fp_line
			(start 0.7874 0.4064)
			(end -0.7874 0.4064)
			(stroke
				(width 0.1524)
				(type default)
			)
			(layer "F.SilkS")
		)
		(fp_line
			(start -0.7874 0.4064)
			(end -0.7874 -0.4064)
			(stroke
				(width 0.1524)
				(type default)
			)
			(layer "F.SilkS")
		)
		(fp_poly
			(pts
				(xy -0.5334 0.254) (xy -0.635 0.254) (xy -0.635 0.2286) (xy -0.635 -0.254) (xy -0.5334 -0.254) (xy -0.5334 -0.2794)
				(xy 0.5334 -0.2794) (xy 0.5334 -0.254) (xy 0.635 -0.254) (xy 0.635 0.254) (xy 0.5334 0.254) (xy 0.5334 0.2794)
				(xy -0.508 0.2794) (xy -0.5334 0.2794)
			)
			(stroke
				(width 0)
				(type default)
			)
			(fill no)
			(layer "F.CrtYd")
		)
		(pad "1" smd rect
			(at 0.40005 0 90)
			(size 0.4572 0.508)
			(layers "F.Cu" "F.Mask" "F.Paste")
			(net "I2C_PSU2_R_SDA")
		)
		(pad "2" smd rect
			(at -0.40005 0 90)
			(size 0.4572 0.508)
			(layers "F.Cu" "F.Mask" "F.Paste")
			(net "GND")
		)
	)
	(footprint ""
		(layer "F.Cu")
		(at 87.445596 -79.428848)
		(property "Reference" "L6"
			(at 2.724404 0.02794 0)
			(unlocked yes)
			(layer "F.SilkS")
			(effects
				(font
					(size 0.7874 0.5842)
					(thickness 0.1524)
				)
				(justify left)
			)
		)
		(property "Value" ""
			(at 0 0 0)
			(layer "F.Fab")
			(effects
				(font
					(size 1.27 1.27)
				)
			)
		)
		(duplicate_pad_numbers_are_jumpers no)
		(fp_line
			(start -0.7874 -0.4064)
			(end 0.7874 -0.4064)
			(stroke
				(width 0.1524)
				(type default)
			)
			(layer "F.SilkS")
		)
		(fp_line
			(start -0.7874 0.4064)
			(end -0.7874 -0.4064)
			(stroke
				(width 0.1524)
				(type default)
			)
			(layer "F.SilkS")
		)
		(fp_line
			(start -0.0889 0.4064)
			(end -0.0889 -0.4064)
			(stroke
				(width 0.1524)
				(type default)
			)
			(layer "F.SilkS")
		)
		(fp_line
			(start 0.0889 0.4064)
			(end 0.0889 -0.4064)
			(stroke
				(width 0.1524)
				(type default)
			)
			(layer "F.SilkS")
		)
		(fp_line
			(start 0.7874 -0.4064)
			(end 0.7874 0.4064)
			(stroke
				(width 0.1524)
				(type default)
			)
			(layer "F.SilkS")
		)
		(fp_line
			(start 0.7874 0.4064)
			(end -0.7874 0.4064)
			(stroke
				(width 0.1524)
				(type default)
			)
			(layer "F.SilkS")
		)
		(fp_poly
			(pts
				(xy -0.5334 0.254) (xy -0.635 0.254) (xy -0.635 0.2286) (xy -0.635 -0.254) (xy -0.5334 -0.254) (xy -0.5334 -0.2794)
				(xy 0.5334 -0.2794) (xy 0.5334 -0.254) (xy 0.635 -0.254) (xy 0.635 0.254) (xy 0.5334 0.254) (xy 0.5334 0.2794)
				(xy -0.508 0.2794) (xy -0.5334 0.2794)
			)
			(stroke
				(width 0)
				(type default)
			)
			(fill no)
			(layer "F.CrtYd")
		)
		(pad "1" smd rect
			(at 0.40005 0)
			(size 0.4572 0.508)
			(layers "F.Cu" "F.Mask" "F.Paste")
			(net "P1V05_NODE1")
		)
		(pad "2" smd rect
			(at -0.40005 0)
			(size 0.4572 0.508)
			(layers "F.Cu" "F.Mask" "F.Paste")
			(net "P1V05_VCCPLLCPU1SIO_NODE1")
		)
	)
)
